(kicad_pcb
	(version 20260206)
	(generator "pcbnew")
	(generator_version "10.0")
	(general
		(thickness 1.6)
		(legacy_teardrops no)
	)
	(paper "A4")
	(title_block
		(title "Bryce Canyon_F.DPB_16315-1-OCP.brd")
		(comment 1 "Bryce Canyon / footprints 2002-2009 of 2223")
	)
	(layers
		(0 "F.Cu" signal "TOP")
		(4 "In1.Cu" signal "L2GND")
		(6 "In2.Cu" signal "L3")
		(8 "In3.Cu" signal "L4GND")
		(10 "In4.Cu" signal "L5")
		(12 "In5.Cu" signal "L6VCC")
		(14 "In6.Cu" signal "L7VCC")
		(16 "In7.Cu" signal "L8")
		(18 "In8.Cu" signal "L9GND")
		(20 "In9.Cu" signal "L10")
		(22 "In10.Cu" signal "L11GND")
		(2 "B.Cu" signal "BOTTOM")
		(9 "F.Adhes" user "F.Adhesive")
		(11 "B.Adhes" user "B.Adhesive")
		(13 "F.Paste" user "Package Geometry/Pastemask Top")
		(15 "B.Paste" user "Package Geometry/Pastemask Bottom")
		(5 "F.SilkS" user "Ref Des/Silkscreen Top")
		(7 "B.SilkS" user "Ref Des/Silkscreen Bottom")
		(1 "F.Mask" user "Board Geometry/Soldermask Top")
		(3 "B.Mask" user "Board Geometry/Soldermask Bottom")
		(17 "Dwgs.User" user "User.Drawings")
		(19 "Cmts.User" user "User.Comments")
		(21 "Eco1.User" user "User.Eco1")
		(23 "Eco2.User" user "User.Eco2")
		(25 "Edge.Cuts" user "Board Geometry/Outline")
		(27 "Margin" user)
		(31 "F.CrtYd" user "Package Geometry/Place Bound Top")
		(29 "B.CrtYd" user "Package Geometry/Place Bound Bottom")
		(35 "F.Fab" user "Ref Des/Assembly Top")
		(33 "B.Fab" user "Ref Des/Assembly Bottom")
	)
	(footprint ""
		(layer "F.Cu")
		(at 64.013334 -44.219368 90)
		(property "Reference" "C363"
			(at 0 0 90)
			(layer "F.SilkS")
			(hide yes)
			(effects
				(font
					(size 1.27 1.27)
				)
			)
		)
		(property "Value" "SCD01U16V1KX-GP"
			(at -2.8321 -1.7399 90)
			(unlocked yes)
			(layer "F.Fab")
			(hide yes)
			(effects
				(font
					(size 1.016 1.016)
					(thickness 0.1524)
				)
			)
		)
		(property "Device Type" "C0201H13"
			(at -2.8321 -3.2639 90)
			(unlocked yes)
			(layer "F.Fab")
			(hide yes)
			(effects
				(font
					(size 1.016 1.016)
					(thickness 0.1524)
				)
			)
		)
		(duplicate_pad_numbers_are_jumpers no)
		(fp_rect
			(start -0.2794 0.6477)
			(end 0.2794 -0.6477)
			(stroke
				(width 0)
				(type default)
			)
			(fill no)
			(layer "F.CrtYd")
		)
		(fp_rect
			(start -0.2794 0.6477)
			(end 0.2794 -0.6477)
			(stroke
				(width 0)
				(type default)
			)
			(fill no)
			(layer "F.Fab")
		)
		(pad "1" smd custom
			(at 0 -0.2794 90)
			(size 0.0762 0.0762)
			(layers "F.Cu" "F.Mask" "F.Paste")
			(net "SAS_HDD_RX_N25")
			(options
				(clearance outline)
				(anchor circle)
			)
			(primitives
				(gr_poly
					(pts
						(arc
							(start 0.1524 -0.127)
							(mid 0.137521 -0.162921)
							(end 0.1016 -0.1778)
						)
						(arc
							(start -0.1016 -0.1778)
							(mid -0.137521 -0.162921)
							(end -0.1524 -0.127)
						)
						(arc
							(start -0.1524 0.127)
							(mid -0.137521 0.162921)
							(end -0.1016 0.1778)
						)
						(arc
							(start 0.1016 0.1778)
							(mid 0.137521 0.162921)
							(end 0.1524 0.127)
						)
					)
					(width 0)
					(fill yes)
				)
			)
		)
		(pad "2" smd custom
			(at 0 0.2794 90)
			(size 0.0762 0.0762)
			(layers "F.Cu" "F.Mask" "F.Paste")
			(net "PHY_SCC_A_TO_DRV_A_25_DN")
			(options
				(clearance outline)
				(anchor circle)
			)
			(primitives
				(gr_poly
					(pts
						(arc
							(start 0.1524 -0.127)
							(mid 0.137521 -0.162921)
							(end 0.1016 -0.1778)
						)
						(arc
							(start -0.1016 -0.1778)
							(mid -0.137521 -0.162921)
							(end -0.1524 -0.127)
						)
						(arc
							(start -0.1524 0.127)
							(mid -0.137521 0.162921)
							(end -0.1016 0.1778)
						)
						(arc
							(start 0.1016 0.1778)
							(mid 0.137521 0.162921)
							(end 0.1524 0.127)
						)
					)
					(width 0)
					(fill yes)
				)
			)
		)
	)
	(footprint ""
		(layer "F.Cu")
		(at 141.548866 -143.594074 180)
		(property "Reference" "R1040"
			(at 0 0 180)
			(layer "F.SilkS")
			(hide yes)
			(effects
				(font
					(size 1.27 1.27)
				)
			)
		)
		(property "Value" "0R2J-2-GP"
			(at 0.064008 -3.993896 180)
			(unlocked yes)
			(layer "F.Fab")
			(hide yes)
			(effects
				(font
					(size 1.016 1.016)
					(thickness 0.1524)
				)
			)
		)
		(property "Device Type" "R402H16"
			(at 0.064008 -5.517896 180)
			(unlocked yes)
			(layer "F.Fab")
			(hide yes)
			(effects
				(font
					(size 1.016 1.016)
					(thickness 0.1524)
				)
			)
		)
		(duplicate_pad_numbers_are_jumpers no)
		(fp_line
			(start 0.508 -0.9398)
			(end -0.508 -0.9398)
			(stroke
				(width 0.1524)
				(type default)
			)
			(layer "F.SilkS")
		)
		(fp_line
			(start -0.508 -0.9398)
			(end -0.508 0.9398)
			(stroke
				(width 0.1524)
				(type default)
			)
			(layer "F.SilkS")
		)
		(fp_rect
			(start -0.508 0.9398)
			(end 0.508 -0.9398)
			(stroke
				(width 0)
				(type default)
			)
			(fill no)
			(layer "F.CrtYd")
		)
		(fp_rect
			(start -0.508 0.9398)
			(end 0.508 -0.9398)
			(stroke
				(width 0)
				(type default)
			)
			(fill no)
			(layer "F.Fab")
		)
		(pad "1" smd custom
			(at 0 -0.4445 180)
			(size 0.1397 0.1397)
			(layers "F.Cu" "F.Mask" "F.Paste")
			(net "MB0_CM_ADR1_R")
			(options
				(clearance outline)
				(anchor circle)
			)
			(primitives
				(gr_poly
					(pts
						(arc
							(start -0.1778 -0.2794)
							(mid -0.249642 -0.249642)
							(end -0.2794 -0.1778)
						)
						(arc
							(start -0.2794 0.1778)
							(mid -0.249642 0.249642)
							(end -0.1778 0.2794)
						)
						(arc
							(start 0.1778 0.2794)
							(mid 0.249642 0.249642)
							(end 0.2794 0.1778)
						)
						(arc
							(start 0.2794 -0.1778)
							(mid 0.249642 -0.249642)
							(end 0.1778 -0.2794)
						)
					)
					(width 0)
					(fill yes)
				)
			)
		)
		(pad "2" smd custom
			(at 0 0.4445 180)
			(size 0.1397 0.1397)
			(layers "F.Cu" "F.Mask" "F.Paste")
			(net "AGND_CURRENT_MONOA")
			(options
				(clearance outline)
				(anchor circle)
			)
			(primitives
				(gr_poly
					(pts
						(arc
							(start -0.1778 -0.2794)
							(mid -0.249642 -0.249642)
							(end -0.2794 -0.1778)
						)
						(arc
							(start -0.2794 0.1778)
							(mid -0.249642 0.249642)
							(end -0.1778 0.2794)
						)
						(arc
							(start 0.1778 0.2794)
							(mid 0.249642 0.249642)
							(end 0.2794 0.1778)
						)
						(arc
							(start 0.2794 -0.1778)
							(mid 0.249642 -0.249642)
							(end 0.1778 -0.2794)
						)
					)
					(width 0)
					(fill yes)
				)
			)
		)
	)
	(footprint ""
		(layer "F.Cu")
		(at 224.572322 -152.19807 -90)
		(property "Reference" "TP207"
			(at 0 0 270)
			(layer "F.SilkS")
			(hide yes)
			(effects
				(font
					(size 1.27 1.27)
				)
			)
		)
		(property "Value" "TPAD32-GP"
			(at -0.0508 -1.6764 270)
			(unlocked yes)
			(layer "F.Fab")
			(hide yes)
			(effects
				(font
					(size 1.016 1.016)
					(thickness 0.1524)
				)
			)
		)
		(property "Device Type" "TPAD32"
			(at -0.0508 -3.2004 270)
			(unlocked yes)
			(layer "F.Fab")
			(hide yes)
			(effects
				(font
					(size 1.016 1.016)
					(thickness 0.1524)
				)
			)
		)
		(duplicate_pad_numbers_are_jumpers no)
		(fp_poly
			(pts
				(arc
					(start 0 -0.4064)
					(mid 0 0.4064)
					(end 0 -0.4064)
				)
			)
			(stroke
				(width 0)
				(type default)
			)
			(fill no)
			(layer "F.CrtYd")
		)
		(fp_poly
			(pts
				(arc
					(start 0 -0.7112)
					(mid 0 0.7112)
					(end 0 -0.7112)
				)
			)
			(stroke
				(width 0)
				(type default)
			)
			(fill no)
			(layer "F.Fab")
		)
		(pad "1" smd circle
			(at 0 0 270)
			(size 0.8128 0.8128)
			(layers "F.Cu" "F.Mask" "F.Paste")
			(net "TP_COMP_A_KR_P0_RX_DP")
		)
	)
	(footprint ""
		(layer "F.Cu")
		(at 237.561374 -231.659938 90)
		(property "Reference" "R17"
			(at 0 0 90)
			(layer "F.SilkS")
			(hide yes)
			(effects
				(font
					(size 1.27 1.27)
				)
			)
		)
		(property "Value" "100KR2F-L1-GP"
			(at 0.064008 -3.993896 90)
			(unlocked yes)
			(layer "F.Fab")
			(hide yes)
			(effects
				(font
					(size 1.016 1.016)
					(thickness 0.1524)
				)
			)
		)
		(property "Device Type" "R402H16"
			(at 0.064008 -5.517896 90)
			(unlocked yes)
			(layer "F.Fab")
			(hide yes)
			(effects
				(font
					(size 1.016 1.016)
					(thickness 0.1524)
				)
			)
		)
		(duplicate_pad_numbers_are_jumpers no)
		(fp_line
			(start 0.508 -0.9398)
			(end -0.508 -0.9398)
			(stroke
				(width 0.1524)
				(type default)
			)
			(layer "F.SilkS")
		)
		(fp_line
			(start -0.508 -0.9398)
			(end -0.508 0.9398)
			(stroke
				(width 0.1524)
				(type default)
			)
			(layer "F.SilkS")
		)
		(fp_rect
			(start -0.508 0.9398)
			(end 0.508 -0.9398)
			(stroke
				(width 0)
				(type default)
			)
			(fill no)
			(layer "F.CrtYd")
		)
		(fp_rect
			(start -0.508 0.9398)
			(end 0.508 -0.9398)
			(stroke
				(width 0)
				(type default)
			)
			(fill no)
			(layer "F.Fab")
		)
		(pad "1" smd custom
			(at 0 -0.4445 90)
			(size 0.1397 0.1397)
			(layers "F.Cu" "F.Mask" "F.Paste")
			(net "GPIO_VCC_U7")
			(options
				(clearance outline)
				(anchor circle)
			)
			(primitives
				(gr_poly
					(pts
						(arc
							(start -0.1778 -0.2794)
							(mid -0.249642 -0.249642)
							(end -0.2794 -0.1778)
						)
						(arc
							(start -0.2794 0.1778)
							(mid -0.249642 0.249642)
							(end -0.1778 0.2794)
						)
						(arc
							(start 0.1778 0.2794)
							(mid 0.249642 0.249642)
							(end 0.2794 0.1778)
						)
						(arc
							(start 0.2794 -0.1778)
							(mid 0.249642 -0.249642)
							(end 0.1778 -0.2794)
						)
					)
					(width 0)
					(fill yes)
				)
			)
		)
		(pad "2" smd custom
			(at 0 0.4445 90)
			(size 0.1397 0.1397)
			(layers "F.Cu" "F.Mask" "F.Paste")
			(net "GND")
			(options
				(clearance outline)
				(anchor circle)
			)
			(primitives
				(gr_poly
					(pts
						(arc
							(start -0.1778 -0.2794)
							(mid -0.249642 -0.249642)
							(end -0.2794 -0.1778)
						)
						(arc
							(start -0.2794 0.1778)
							(mid -0.249642 0.249642)
							(end -0.1778 0.2794)
						)
						(arc
							(start 0.1778 0.2794)
							(mid 0.249642 0.249642)
							(end 0.2794 0.1778)
						)
						(arc
							(start 0.2794 -0.1778)
							(mid 0.249642 -0.249642)
							(end 0.1778 -0.2794)
						)
					)
					(width 0)
					(fill yes)
				)
			)
		)
	)
	(footprint ""
		(layer "F.Cu")
		(at 338.709 -287.851342 90)
		(property "Reference" "C127"
			(at 0 0 90)
			(layer "F.SilkS")
			(hide yes)
			(effects
				(font
					(size 1.27 1.27)
				)
			)
		)
		(property "Value" "SCD033U25V2KX-GP"
			(at 1.1811 -2.7051 90)
			(unlocked yes)
			(layer "F.Fab")
			(hide yes)
			(effects
				(font
					(size 1.016 1.016)
					(thickness 0.1524)
				)
			)
		)
		(property "Device Type" "C402H22"
			(at 1.1811 -4.2291 90)
			(unlocked yes)
			(layer "F.Fab")
			(hide yes)
			(effects
				(font
					(size 1.016 1.016)
					(thickness 0.1524)
				)
			)
		)
		(duplicate_pad_numbers_are_jumpers no)
		(fp_rect
			(start -0.4318 0.9525)
			(end 0.4318 -0.9525)
			(stroke
				(width 0)
				(type default)
			)
			(fill no)
			(layer "F.CrtYd")
		)
		(fp_rect
			(start -0.4318 0.9525)
			(end 0.4318 -0.9525)
			(stroke
				(width 0)
				(type default)
			)
			(fill no)
			(layer "F.Fab")
		)
		(pad "1" smd custom
			(at 0 -0.4445 90)
			(size 0.1524 0.1524)
			(layers "F.Cu" "F.Mask" "F.Paste")
			(net "P12V_A")
			(options
				(clearance outline)
				(anchor circle)
			)
			(primitives
				(gr_poly
					(pts
						(arc
							(start 0.3048 -0.2032)
							(mid 0.275042 -0.275042)
							(end 0.2032 -0.3048)
						)
						(arc
							(start -0.2032 -0.3048)
							(mid -0.275042 -0.275042)
							(end -0.3048 -0.2032)
						)
						(arc
							(start -0.3048 0.2032)
							(mid -0.275042 0.275042)
							(end -0.2032 0.3048)
						)
						(arc
							(start 0.2032 0.3048)
							(mid 0.275042 0.275042)
							(end 0.3048 0.2032)
						)
					)
					(width 0)
					(fill yes)
				)
			)
		)
		(pad "2" smd custom
			(at 0 0.4445 90)
			(size 0.1524 0.1524)
			(layers "F.Cu" "F.Mask" "F.Paste")
			(net "SW_HDD_N6")
			(options
				(clearance outline)
				(anchor circle)
			)
			(primitives
				(gr_poly
					(pts
						(arc
							(start 0.3048 -0.2032)
							(mid 0.275042 -0.275042)
							(end 0.2032 -0.3048)
						)
						(arc
							(start -0.2032 -0.3048)
							(mid -0.275042 -0.275042)
							(end -0.3048 -0.2032)
						)
						(arc
							(start -0.3048 0.2032)
							(mid -0.275042 0.275042)
							(end -0.2032 0.3048)
						)
						(arc
							(start 0.2032 0.3048)
							(mid 0.275042 0.275042)
							(end 0.3048 0.2032)
						)
					)
					(width 0)
					(fill yes)
				)
			)
		)
	)
	(footprint ""
		(layer "F.Cu")
		(at 284.4038 -272.3134)
		(property "Reference" "R126"
			(at 0 0 0)
			(layer "F.SilkS")
			(hide yes)
			(effects
				(font
					(size 1.27 1.27)
				)
			)
		)
		(property "Value" "4K7R2F-GP"
			(at 0.064008 -3.993896 0)
			(unlocked yes)
			(layer "F.Fab")
			(hide yes)
			(effects
				(font
					(size 1.016 1.016)
					(thickness 0.1524)
				)
			)
		)
		(property "Device Type" "R402H16"
			(at 0.064008 -5.517896 0)
			(unlocked yes)
			(layer "F.Fab")
			(hide yes)
			(effects
				(font
					(size 1.016 1.016)
					(thickness 0.1524)
				)
			)
		)
		(duplicate_pad_numbers_are_jumpers no)
		(fp_line
			(start -0.508 -0.9398)
			(end -0.508 0.9398)
			(stroke
				(width 0.1524)
				(type default)
			)
			(layer "F.SilkS")
		)
		(fp_line
			(start 0.508 -0.9398)
			(end -0.508 -0.9398)
			(stroke
				(width 0.1524)
				(type default)
			)
			(layer "F.SilkS")
		)
		(fp_rect
			(start -0.508 0.9398)
			(end 0.508 -0.9398)
			(stroke
				(width 0)
				(type default)
			)
			(fill no)
			(layer "F.CrtYd")
		)
		(fp_rect
			(start -0.508 0.9398)
			(end 0.508 -0.9398)
			(stroke
				(width 0)
				(type default)
			)
			(fill no)
			(layer "F.Fab")
		)
		(pad "1" smd custom
			(at 0 -0.4445)
			(size 0.1397 0.1397)
			(layers "F.Cu" "F.Mask" "F.Paste")
			(net "IO_EXP2_HDD_FAULT_A1")
			(options
				(clearance outline)
				(anchor circle)
			)
			(primitives
				(gr_poly
					(pts
						(arc
							(start -0.1778 -0.2794)
							(mid -0.249642 -0.249642)
							(end -0.2794 -0.1778)
						)
						(arc
							(start -0.2794 0.1778)
							(mid -0.249642 0.249642)
							(end -0.1778 0.2794)
						)
						(arc
							(start 0.1778 0.2794)
							(mid 0.249642 0.249642)
							(end 0.2794 0.1778)
						)
						(arc
							(start 0.2794 -0.1778)
							(mid 0.249642 -0.249642)
							(end 0.1778 -0.2794)
						)
					)
					(width 0)
					(fill yes)
				)
			)
		)
		(pad "2" smd custom
			(at 0 0.4445)
			(size 0.1397 0.1397)
			(layers "F.Cu" "F.Mask" "F.Paste")
			(net "GND")
			(options
				(clearance outline)
				(anchor circle)
			)
			(primitives
				(gr_poly
					(pts
						(arc
							(start -0.1778 -0.2794)
							(mid -0.249642 -0.249642)
							(end -0.2794 -0.1778)
						)
						(arc
							(start -0.2794 0.1778)
							(mid -0.249642 0.249642)
							(end -0.1778 0.2794)
						)
						(arc
							(start 0.1778 0.2794)
							(mid 0.249642 0.249642)
							(end 0.2794 0.1778)
						)
						(arc
							(start 0.2794 -0.1778)
							(mid 0.249642 -0.249642)
							(end 0.1778 -0.2794)
						)
					)
					(width 0)
					(fill yes)
				)
			)
		)
	)
	(footprint ""
		(layer "F.Cu")
		(at 471.275918 -156.522674)
		(property "Reference" "R671"
			(at 0 0 0)
			(layer "F.SilkS")
			(hide yes)
			(effects
				(font
					(size 1.27 1.27)
				)
			)
		)
		(property "Value" "4K7R2J-2-GP"
			(at 0.064008 -3.993896 0)
			(unlocked yes)
			(layer "F.Fab")
			(hide yes)
			(effects
				(font
					(size 1.016 1.016)
					(thickness 0.1524)
				)
			)
		)
		(property "Device Type" "R402H16"
			(at 0.064008 -5.517896 0)
			(unlocked yes)
			(layer "F.Fab")
			(hide yes)
			(effects
				(font
					(size 1.016 1.016)
					(thickness 0.1524)
				)
			)
		)
		(duplicate_pad_numbers_are_jumpers no)
		(fp_line
			(start -0.508 -0.9398)
			(end -0.508 0.9398)
			(stroke
				(width 0.1524)
				(type default)
			)
			(layer "F.SilkS")
		)
		(fp_line
			(start 0.508 -0.9398)
			(end -0.508 -0.9398)
			(stroke
				(width 0.1524)
				(type default)
			)
			(layer "F.SilkS")
		)
		(fp_rect
			(start -0.508 0.9398)
			(end 0.508 -0.9398)
			(stroke
				(width 0)
				(type default)
			)
			(fill no)
			(layer "F.CrtYd")
		)
		(fp_rect
			(start -0.508 0.9398)
			(end 0.508 -0.9398)
			(stroke
				(width 0)
				(type default)
			)
			(fill no)
			(layer "F.Fab")
		)
		(pad "1" smd custom
			(at 0 -0.4445)
			(size 0.1397 0.1397)
			(layers "F.Cu" "F.Mask" "F.Paste")
			(net "SW_PWR_R_HDD23")
			(options
				(clearance outline)
				(anchor circle)
			)
			(primitives
				(gr_poly
					(pts
						(arc
							(start -0.1778 -0.2794)
							(mid -0.249642 -0.249642)
							(end -0.2794 -0.1778)
						)
						(arc
							(start -0.2794 0.1778)
							(mid -0.249642 0.249642)
							(end -0.1778 0.2794)
						)
						(arc
							(start 0.1778 0.2794)
							(mid 0.249642 0.249642)
							(end 0.2794 0.1778)
						)
						(arc
							(start 0.2794 -0.1778)
							(mid 0.249642 -0.249642)
							(end 0.1778 -0.2794)
						)
					)
					(width 0)
					(fill yes)
				)
			)
		)
		(pad "2" smd custom
			(at 0 0.4445)
			(size 0.1397 0.1397)
			(layers "F.Cu" "F.Mask" "F.Paste")
			(net "GND")
			(options
				(clearance outline)
				(anchor circle)
			)
			(primitives
				(gr_poly
					(pts
						(arc
							(start -0.1778 -0.2794)
							(mid -0.249642 -0.249642)
							(end -0.2794 -0.1778)
						)
						(arc
							(start -0.2794 0.1778)
							(mid -0.249642 0.249642)
							(end -0.1778 0.2794)
						)
						(arc
							(start 0.1778 0.2794)
							(mid 0.249642 0.249642)
							(end 0.2794 0.1778)
						)
						(arc
							(start 0.2794 -0.1778)
							(mid 0.249642 -0.249642)
							(end 0.1778 -0.2794)
						)
					)
					(width 0)
					(fill yes)
				)
			)
		)
	)
	(footprint ""
		(layer "F.Cu")
		(at 20.049998 -176.000918 -90)
		(property "Reference" "C197"
			(at 0 0 270)
			(layer "F.SilkS")
			(hide yes)
			(effects
				(font
					(size 1.27 1.27)
				)
			)
		)
		(property "Value" "SC10U16V6KX-2GP"
			(at -0.0762 -5.1308 270)
			(unlocked yes)
			(layer "F.Fab")
			(hide yes)
			(effects
				(font
					(size 1.016 1.016)
					(thickness 0.1524)
				)
			)
		)
		(property "Device Type" "C1206H71"
			(at -0.127 -6.6548 270)
			(unlocked yes)
			(layer "F.Fab")
			(hide yes)
			(effects
				(font
					(size 1.016 1.016)
					(thickness 0.1524)
				)
			)
		)
		(duplicate_pad_numbers_are_jumpers no)
		(fp_line
			(start -1.016 2.2352)
			(end -1.016 0.8382)
			(stroke
				(width 0.1524)
				(type default)
			)
			(layer "F.SilkS")
		)
		(fp_line
			(start 1.016 2.2352)
			(end -1.016 2.2352)
			(stroke
				(width 0.1524)
				(type default)
			)
			(layer "F.SilkS")
		)
		(fp_line
			(start 1.016 0.8382)
			(end 1.016 2.2352)
			(stroke
				(width 0.1524)
				(type default)
			)
			(layer "F.SilkS")
		)
		(fp_line
			(start -1.016 -0.8382)
			(end -1.016 -2.2352)
			(stroke
				(width 0.1524)
				(type default)
			)
			(layer "F.SilkS")
		)
		(fp_line
			(start -1.016 -2.2352)
			(end 1.016 -2.2352)
			(stroke
				(width 0.1524)
				(type default)
			)
			(layer "F.SilkS")
		)
		(fp_line
			(start 1.016 -2.2352)
			(end 1.016 -0.8382)
			(stroke
				(width 0.1524)
				(type default)
			)
			(layer "F.SilkS")
		)
		(fp_rect
			(start -1.0922 2.3114)
			(end 1.0922 -2.3114)
			(stroke
				(width 0)
				(type default)
			)
			(fill no)
			(layer "F.CrtYd")
		)
		(fp_poly
			(pts
				(xy 1.0922 -2.3114) (xy 1.0922 2.3114) (xy -1.0922 2.3114) (xy -1.0922 -2.3114)
			)
			(stroke
				(width 0)
				(type default)
			)
			(fill no)
			(layer "F.Fab")
		)
		(pad "1" smd rect
			(at 0 -1.397 270)
			(size 1.651 1.27)
			(layers "F.Cu" "F.Mask" "F.Paste")
			(net "P5V_HDD12")
		)
		(pad "2" smd rect
			(at 0 1.397 270)
			(size 1.651 1.27)
			(layers "F.Cu" "F.Mask" "F.Paste")
			(net "GND")
		)
	)
)
